# SCM (Grand Teton) — schematic netlist excerpt (pin names and nets, part order shuffled) for the footprints in the layout excerpt that follows; sources: Cadence DE-HDL packaged netlist, KiCad conversion of 12092022_DA0F0TMDCD0_F0T_Management_Board_D_brd_V3_OCP.brd

R221  Q_RES  33.2 1% CHIP  pkg 0402LF  page 32 : A = JTAG_1_BMC_TRST_R ; B = JTAG_MB_TRST_N
L5  Q_INDUCTOR  BLM18PG121SN1D/2000MA IND  pkg SMLF  page 17 : \1\ = P1V8_AUX ; \2\ = P1V8_STBY_AVDDPLL

(kicad_pcb
	(version 20260206)
	(generator "pcbnew")
	(generator_version "10.0")
	(general
		(thickness 1.6)
		(legacy_teardrops no)
	)
	(paper "A4")
	(title_block
		(title "12092022_DA0F0TMDCD0_F0T_Management_Board_D_brd_V3_OCP.brd")
		(comment 1 "Grand Teton / footprints 775-776 of 1440")
	)
	(layers
		(0 "F.Cu" signal "TOP")
		(4 "In1.Cu" signal "GND")
		(6 "In2.Cu" signal "IN1")
		(8 "In3.Cu" signal "GND1")
		(10 "In4.Cu" signal "IN2")
		(12 "In5.Cu" signal "VCC")
		(14 "In6.Cu" signal "VCC1")
		(16 "In7.Cu" signal "IN3")
		(18 "In8.Cu" signal "GND2")
		(20 "In9.Cu" signal "IN4")
		(22 "In10.Cu" signal "GND3")
		(2 "B.Cu" signal "BOTTOM")
		(9 "F.Adhes" user "F.Adhesive")
		(11 "B.Adhes" user "B.Adhesive")
		(13 "F.Paste" user "Package Geometry/Pastemask Top")
		(15 "B.Paste" user "Package Geometry/Pastemask Bottom")
		(5 "F.SilkS" user "Ref Des/Silkscreen Top")
		(7 "B.SilkS" user "Ref Des/Silkscreen Bottom")
		(1 "F.Mask" user "Board Geometry/Soldermask Top")
		(3 "B.Mask" user "Board Geometry/Soldermask Bottom")
		(17 "Dwgs.User" user "User.Drawings")
		(19 "Cmts.User" user "User.Comments")
		(21 "Eco1.User" user "User.Eco1")
		(23 "Eco2.User" user "User.Eco2")
		(25 "Edge.Cuts" user "Board Geometry/Outline")
		(27 "Margin" user)
		(31 "F.CrtYd" user "Package Geometry/Place Bound Top")
		(29 "B.CrtYd" user "Package Geometry/Place Bound Bottom")
		(35 "F.Fab" user "Ref Des/Assembly Top")
		(33 "B.Fab" user "Ref Des/Assembly Bottom")
	)
	(footprint ""
		(layer "B.Cu")
		(at 69.166994 -37.05479 90)
		(property "Reference" "L5"
			(at 0 0 90)
			(layer "B.SilkS")
			(hide yes)
			(effects
				(font
					(size 1.27 1.27)
				)
				(justify mirror)
			)
		)
		(property "Value" ""
			(at 0 0 90)
			(layer "B.Fab")
			(effects
				(font
					(size 1.27 1.27)
				)
				(justify mirror)
			)
		)
		(duplicate_pad_numbers_are_jumpers no)
		(fp_line
			(start 1.27 -0.5842)
			(end -1.27 -0.5842)
			(stroke
				(width 0.1524)
				(type default)
			)
			(layer "B.SilkS")
		)
		(fp_line
			(start 1.27 -0.5588)
			(end 1.27 -0.5842)
			(stroke
				(width 0.1524)
				(type default)
			)
			(layer "B.SilkS")
		)
		(fp_line
			(start 1.27 0.5842)
			(end 1.27 -0.5842)
			(stroke
				(width 0.1524)
				(type default)
			)
			(layer "B.SilkS")
		)
		(fp_line
			(start 0.127 0.5842)
			(end 0.127 -0.5842)
			(stroke
				(width 0.1524)
				(type default)
			)
			(layer "B.SilkS")
		)
		(fp_line
			(start -0.127 0.5842)
			(end -0.127 -0.5842)
			(stroke
				(width 0.1524)
				(type default)
			)
			(layer "B.SilkS")
		)
		(fp_line
			(start -1.27 0.5842)
			(end -1.27 -0.5842)
			(stroke
				(width 0.1524)
				(type default)
			)
			(layer "B.SilkS")
		)
		(fp_line
			(start -1.27 0.5842)
			(end 1.27 0.5842)
			(stroke
				(width 0.1524)
				(type default)
			)
			(layer "B.SilkS")
		)
		(fp_line
			(start 0.9144 -0.508)
			(end -0.9144 -0.508)
			(stroke
				(width 0.1)
				(type default)
			)
			(layer "B.Fab")
		)
		(fp_line
			(start -0.9144 -0.508)
			(end -0.9144 -0.406654)
			(stroke
				(width 0.1)
				(type default)
			)
			(layer "B.Fab")
		)
		(fp_line
			(start 1.194308 -0.406654)
			(end 0.9144 -0.406654)
			(stroke
				(width 0.1)
				(type default)
			)
			(layer "B.Fab")
		)
		(fp_line
			(start 0.9144 -0.406654)
			(end 0.9144 -0.508)
			(stroke
				(width 0.1)
				(type default)
			)
			(layer "B.Fab")
		)
		(fp_line
			(start -0.9144 -0.406654)
			(end -1.1938 -0.406654)
			(stroke
				(width 0.1)
				(type default)
			)
			(layer "B.Fab")
		)
		(fp_line
			(start -1.1938 -0.406654)
			(end -1.1938 0.4064)
			(stroke
				(width 0.1)
				(type default)
			)
			(layer "B.Fab")
		)
		(fp_line
			(start -0.9144 0.4064)
			(end -0.9144 0.508)
			(stroke
				(width 0.1)
				(type default)
			)
			(layer "B.Fab")
		)
		(fp_line
			(start -1.1938 0.4064)
			(end -0.9144 0.4064)
			(stroke
				(width 0.1)
				(type default)
			)
			(layer "B.Fab")
		)
		(fp_line
			(start 1.194308 0.406654)
			(end 1.194308 -0.406654)
			(stroke
				(width 0.1)
				(type default)
			)
			(layer "B.Fab")
		)
		(fp_line
			(start 0.9144 0.406654)
			(end 1.194308 0.406654)
			(stroke
				(width 0.1)
				(type default)
			)
			(layer "B.Fab")
		)
		(fp_line
			(start 0.9144 0.508)
			(end 0.9144 0.406654)
			(stroke
				(width 0.1)
				(type default)
			)
			(layer "B.Fab")
		)
		(fp_line
			(start -0.9144 0.508)
			(end 0.9144 0.508)
			(stroke
				(width 0.1)
				(type default)
			)
			(layer "B.Fab")
		)
		(pad "1" smd rect
			(at 0.7366 0)
			(size 0.7112 0.8128)
			(layers "B.Cu" "B.Mask" "B.Paste")
			(net "P1V8_AUX")
		)
		(pad "2" smd rect
			(at -0.7366 0)
			(size 0.7112 0.8128)
			(layers "B.Cu" "B.Mask" "B.Paste")
			(net "P1V8_STBY_AVDDPLL")
		)
	)
	(footprint ""
		(layer "B.Cu")
		(at 51.5366 -34.671 90)
		(property "Reference" "R221"
			(at 0 0 90)
			(layer "B.SilkS")
			(hide yes)
			(effects
				(font
					(size 1.27 1.27)
				)
				(justify mirror)
			)
		)
		(property "Value" ""
			(at 0 0 90)
			(layer "B.Fab")
			(effects
				(font
					(size 1.27 1.27)
				)
				(justify mirror)
			)
		)
		(duplicate_pad_numbers_are_jumpers no)
		(fp_line
			(start 0.7874 -0.4064)
			(end -0.7874 -0.4064)
			(stroke
				(width 0.1524)
				(type default)
			)
			(layer "B.SilkS")
		)
		(fp_line
			(start -0.7874 -0.4064)
			(end -0.7874 0.4064)
			(stroke
				(width 0.1524)
				(type default)
			)
			(layer "B.SilkS")
		)
		(fp_line
			(start 0.7874 0.4064)
			(end 0.7874 -0.4064)
			(stroke
				(width 0.1524)
				(type default)
			)
			(layer "B.SilkS")
		)
		(fp_line
			(start -0.7874 0.4064)
			(end 0.7874 0.4064)
			(stroke
				(width 0.1524)
				(type default)
			)
			(layer "B.SilkS")
		)
		(fp_line
			(start 0.67945 -0.305054)
			(end 0.12065 -0.305054)
			(stroke
				(width 0.1)
				(type default)
			)
			(layer "B.Fab")
		)
		(fp_line
			(start 0.12065 -0.305054)
			(end 0.12065 -0.2794)
			(stroke
				(width 0.1)
				(type default)
			)
			(layer "B.Fab")
		)
		(fp_line
			(start -0.12065 -0.3048)
			(end -0.67945 -0.3048)
			(stroke
				(width 0.1)
				(type default)
			)
			(layer "B.Fab")
		)
		(fp_line
			(start -0.67945 -0.3048)
			(end -0.67945 0.3048)
			(stroke
				(width 0.1)
				(type default)
			)
			(layer "B.Fab")
		)
		(fp_line
			(start 0.12065 -0.2794)
			(end -0.12065 -0.2794)
			(stroke
				(width 0.1)
				(type default)
			)
			(layer "B.Fab")
		)
		(fp_line
			(start -0.12065 -0.2794)
			(end -0.12065 -0.3048)
			(stroke
				(width 0.1)
				(type default)
			)
			(layer "B.Fab")
		)
		(fp_line
			(start 0.12065 0.2794)
			(end 0.12065 0.3048)
			(stroke
				(width 0.1)
				(type default)
			)
			(layer "B.Fab")
		)
		(fp_line
			(start -0.120396 0.2794)
			(end 0.12065 0.2794)
			(stroke
				(width 0.1)
				(type default)
			)
			(layer "B.Fab")
		)
		(fp_line
			(start 0.67945 0.3048)
			(end 0.67945 -0.305054)
			(stroke
				(width 0.1)
				(type default)
			)
			(layer "B.Fab")
		)
		(fp_line
			(start 0.12065 0.3048)
			(end 0.67945 0.3048)
			(stroke
				(width 0.1)
				(type default)
			)
			(layer "B.Fab")
		)
		(fp_line
			(start -0.120396 0.3048)
			(end -0.120396 0.2794)
			(stroke
				(width 0.1)
				(type default)
			)
			(layer "B.Fab")
		)
		(fp_line
			(start -0.67945 0.3048)
			(end -0.120396 0.3048)
			(stroke
				(width 0.1)
				(type default)
			)
			(layer "B.Fab")
		)
		(pad "1" smd circle
			(at 0.40005 0 270)
			(size 0 0)
			(layers "B.Cu" "B.Mask" "B.Paste")
			(net "JTAG_1_BMC_TRST_R")
		)
		(pad "2" smd circle
			(at -0.40005 0 270)
			(size 0 0)
			(layers "B.Cu" "B.Mask" "B.Paste")
			(net "JTAG_MB_TRST_N")
		)
	)
)
